# TIMECARD (Time Appliance Project (Time Card)) — schematic netlist excerpt (pin names and nets, part order shuffled) for the footprints in the layout excerpt that follows; sources: Cadence DE-HDL packaged netlist, KiCad conversion of R4006-B0001-02_R01.brd

TP2  TP_PIONT  pkg TP010CT020B030_PTH  page 20 : \1\ = BNO080_EVN_SCL
C40  CAPACITOR  0.1UF 25V 10%  pkg SMC_0402R_H022  page 18 : \1\ = XP3R3V_FPGA ; \2\ = SG
C270  CAPACITOR  47UF 4V 20%  pkg SMC_0805R_H057  page 29 : \1\ = XP1R0V_FPGA ; \2\ = SG

(kicad_pcb
	(version 20260206)
	(generator "pcbnew")
	(generator_version "10.0")
	(general
		(thickness 1.6)
		(legacy_teardrops no)
	)
	(paper "A4")
	(title_block
		(title "timecard-production-celestica-r4006 — R4006-B0001-02_R01.brd")
		(comment 1 "Time Appliance Project (Time Card) / footprints 176-178 of 1113")
	)
	(layers
		(0 "F.Cu" signal "TOP")
		(4 "In1.Cu" signal "L02_GND1")
		(6 "In2.Cu" signal "L03_SIG1")
		(8 "In3.Cu" signal "L04_GND2")
		(10 "In4.Cu" signal "L05_VCC1")
		(12 "In5.Cu" signal "L06_VCC2")
		(14 "In6.Cu" signal "L07_GND3")
		(16 "In7.Cu" signal "L08_SIG2")
		(18 "In8.Cu" signal "L09_GND4")
		(2 "B.Cu" signal "BOTTOM")
		(9 "F.Adhes" user "F.Adhesive")
		(11 "B.Adhes" user "B.Adhesive")
		(13 "F.Paste" user "Package Geometry/Pastemask Top")
		(15 "B.Paste" user "Package Geometry/Pastemask Bottom")
		(5 "F.SilkS" user "Ref Des/Silkscreen Top")
		(7 "B.SilkS" user "Ref Des/Silkscreen Bottom")
		(1 "F.Mask" user "Board Geometry/Soldermask Top")
		(3 "B.Mask" user "Board Geometry/Soldermask Bottom")
		(17 "Dwgs.User" user "User.Drawings")
		(19 "Cmts.User" user "User.Comments")
		(21 "Eco1.User" user "User.Eco1")
		(23 "Eco2.User" user "User.Eco2")
		(25 "Edge.Cuts" user "Board Geometry/Outline")
		(27 "Margin" user)
		(31 "F.CrtYd" user "Package Geometry/Place Bound Top")
		(29 "B.CrtYd" user "Package Geometry/Place Bound Bottom")
		(35 "F.Fab" user "Ref Des/Assembly Top")
		(33 "B.Fab" user "Ref Des/Assembly Bottom")
	)
	(footprint ""
		(layer "F.Cu")
		(at 155.9814 -58.3946 -90)
		(property "Reference" "C40"
			(at -3.3274 -0.26797 90)
			(unlocked yes)
			(layer "F.SilkS")
			(effects
				(font
					(size 0.7874 0.5842)
					(thickness 0.1524)
				)
			)
		)
		(property "Value" "VAL*"
			(at 0.0762 2.067306 270)
			(unlocked yes)
			(layer "F.Fab")
			(hide yes)
			(effects
				(font
					(size 0.7874 0.5842)
					(thickness 0.1524)
				)
			)
		)
		(property "Device Type" "CAPACITOR-G105-0B104-EK,0.1UF,A"
			(at 0.0508 1.127506 270)
			(unlocked yes)
			(layer "F.Fab")
			(hide yes)
			(effects
				(font
					(size 0.7874 0.5842)
					(thickness 0.1524)
				)
			)
		)
		(property "User Part Number" "PARTNUM*"
			(at 0.1016 4.023106 270)
			(unlocked yes)
			(layer "Cmts.User")
			(hide yes)
			(effects
				(font
					(size 0.7874 0.5842)
					(thickness 0.1524)
				)
			)
		)
		(property "Tolerance" "TOL*"
			(at 0.0762 3.032506 270)
			(unlocked yes)
			(layer "Cmts.User")
			(hide yes)
			(effects
				(font
					(size 0.7874 0.5842)
					(thickness 0.1524)
				)
			)
		)
		(duplicate_pad_numbers_are_jumpers no)
		(fp_line
			(start -1.143 0.5588)
			(end 1.143 0.5588)
			(stroke
				(width 0.1)
				(type default)
			)
			(layer "F.SilkS")
		)
		(fp_line
			(start 1.143 0.5588)
			(end 1.143 -0.5588)
			(stroke
				(width 0.1)
				(type default)
			)
			(layer "F.SilkS")
		)
		(fp_line
			(start -1.143 -0.5588)
			(end -1.143 0.5588)
			(stroke
				(width 0.1)
				(type default)
			)
			(layer "F.SilkS")
		)
		(fp_line
			(start 1.143 -0.5588)
			(end -1.143 -0.5588)
			(stroke
				(width 0.1)
				(type default)
			)
			(layer "F.SilkS")
		)
		(fp_rect
			(start -1.143 0.5588)
			(end 1.143 -0.5588)
			(stroke
				(width 0)
				(type default)
			)
			(fill no)
			(layer "F.CrtYd")
		)
		(fp_line
			(start -0.508 0.3048)
			(end 0.508 0.3048)
			(stroke
				(width 0.1)
				(type default)
			)
			(layer "F.Fab")
		)
		(fp_line
			(start 0.508 0.3048)
			(end 0.508 -0.3048)
			(stroke
				(width 0.1)
				(type default)
			)
			(layer "F.Fab")
		)
		(fp_line
			(start -0.508 -0.3048)
			(end -0.508 0.3048)
			(stroke
				(width 0.1)
				(type default)
			)
			(layer "F.Fab")
		)
		(fp_line
			(start 0.508 -0.3048)
			(end -0.508 -0.3048)
			(stroke
				(width 0.1)
				(type default)
			)
			(layer "F.Fab")
		)
		(pad "1" smd rect
			(at -0.5334 0 270)
			(size 0.7112 0.6096)
			(layers "F.Cu" "F.Mask" "F.Paste")
			(net "XP3R3V_FPGA")
		)
		(pad "2" smd rect
			(at 0.5334 0 270)
			(size 0.7112 0.6096)
			(layers "F.Cu" "F.Mask" "F.Paste")
			(net "SG")
		)
		(zone
			(layer "F.Cu")
			(hatch none 0.5)
			(connect_pads
				(clearance 0)
			)
			(min_thickness 0.25)
			(keepout
				(tracks allowed)
				(vias not_allowed)
				(pads allowed)
				(copperpour not_allowed)
				(footprints allowed)
			)
			(placement
				(enabled no)
				(sheetname "")
			)
			(fill
				(thermal_gap 0.5)
				(thermal_bridge_width 0.5)
				(island_removal_mode 0)
			)
			(polygon
				(pts
					(xy 155.6766 -58.4708) (xy 155.6766 -58.3184) (xy 156.2862 -58.3184) (xy 156.2862 -58.4708)
				)
			)
		)
	)
	(footprint ""
		(layer "F.Cu")
		(at 135.89 -46.228 90)
		(property "Reference" "C270"
			(at 3.302 -0.35433 90)
			(unlocked yes)
			(layer "F.SilkS")
			(effects
				(font
					(size 0.7874 0.5842)
					(thickness 0.1524)
				)
			)
		)
		(property "Value" "VAL*"
			(at 0.0762 3.134106 90)
			(unlocked yes)
			(layer "F.Fab")
			(hide yes)
			(effects
				(font
					(size 0.7874 0.5842)
					(thickness 0.1524)
				)
			)
		)
		(property "Device Type" "CAPACITOR-G107-0F476-AM,47UF,2A"
			(at 0.0508 2.194306 90)
			(unlocked yes)
			(layer "F.Fab")
			(hide yes)
			(effects
				(font
					(size 0.7874 0.5842)
					(thickness 0.1524)
				)
			)
		)
		(property "User Part Number" "PARTNUM*"
			(at 0.1016 5.013706 90)
			(unlocked yes)
			(layer "Cmts.User")
			(hide yes)
			(effects
				(font
					(size 0.7874 0.5842)
					(thickness 0.1524)
				)
			)
		)
		(property "Tolerance" "TOL*"
			(at 0.0762 4.048506 90)
			(unlocked yes)
			(layer "Cmts.User")
			(hide yes)
			(effects
				(font
					(size 0.7874 0.5842)
					(thickness 0.1524)
				)
			)
		)
		(duplicate_pad_numbers_are_jumpers no)
		(fp_line
			(start 1.5748 -0.9398)
			(end -1.5748 -0.9398)
			(stroke
				(width 0.1)
				(type default)
			)
			(layer "F.SilkS")
		)
		(fp_line
			(start -1.5748 -0.9398)
			(end -1.5748 0.9398)
			(stroke
				(width 0.1)
				(type default)
			)
			(layer "F.SilkS")
		)
		(fp_line
			(start 1.5748 0.9398)
			(end 1.5748 -0.9398)
			(stroke
				(width 0.1)
				(type default)
			)
			(layer "F.SilkS")
		)
		(fp_line
			(start -1.5748 0.9398)
			(end 1.5748 0.9398)
			(stroke
				(width 0.1)
				(type default)
			)
			(layer "F.SilkS")
		)
		(fp_rect
			(start -1.5748 -0.9398)
			(end 1.5748 0.9398)
			(stroke
				(width 0)
				(type default)
			)
			(fill no)
			(layer "F.CrtYd")
		)
		(fp_line
			(start 1.016 -0.635)
			(end -1.016 -0.635)
			(stroke
				(width 0.1)
				(type default)
			)
			(layer "F.Fab")
		)
		(fp_line
			(start -1.016 -0.635)
			(end -1.016 0.635)
			(stroke
				(width 0.1)
				(type default)
			)
			(layer "F.Fab")
		)
		(fp_line
			(start 1.016 0.635)
			(end 1.016 -0.635)
			(stroke
				(width 0.1)
				(type default)
			)
			(layer "F.Fab")
		)
		(fp_line
			(start -1.016 0.635)
			(end 1.016 0.635)
			(stroke
				(width 0.1)
				(type default)
			)
			(layer "F.Fab")
		)
		(pad "1" smd rect
			(at -0.8382 0 90)
			(size 0.9652 1.3716)
			(layers "F.Cu" "F.Mask" "F.Paste")
			(net "XP1R0V_FPGA")
		)
		(pad "2" smd rect
			(at 0.8382 0 90)
			(size 0.9652 1.3716)
			(layers "F.Cu" "F.Mask" "F.Paste")
			(net "SG")
		)
		(zone
			(layer "F.Cu")
			(hatch none 0.5)
			(connect_pads
				(clearance 0)
			)
			(min_thickness 0.25)
			(keepout
				(tracks allowed)
				(vias not_allowed)
				(pads allowed)
				(copperpour not_allowed)
				(footprints allowed)
			)
			(placement
				(enabled no)
				(sheetname "")
			)
			(fill
				(thermal_gap 0.5)
				(thermal_bridge_width 0.5)
				(island_removal_mode 0)
			)
			(polygon
				(pts
					(xy 135.255 -45.9994) (xy 136.525 -45.9994) (xy 136.525 -46.4566) (xy 135.255 -46.4566)
				)
			)
		)
	)
	(footprint ""
		(layer "F.Cu")
		(at 82.296 -76.454 -90)
		(property "Reference" "TP2"
			(at 0 0 270)
			(layer "F.SilkS")
			(hide yes)
			(effects
				(font
					(size 1.27 1.27)
				)
			)
		)
		(property "Value" ""
			(at 0 0 270)
			(layer "F.Fab")
			(effects
				(font
					(size 1.27 1.27)
				)
			)
		)
		(property "Device Type" "TP_PIONT-TP010CT020B030_PTH-TPA"
			(at -1.341882 0.996696 270)
			(unlocked yes)
			(layer "F.Fab")
			(hide yes)
			(effects
				(font
					(size 0.7874 0.5842)
					(thickness 0.1524)
				)
				(justify left)
			)
		)
		(duplicate_pad_numbers_are_jumpers no)
		(fp_poly
			(pts
				(arc
					(start 0 -0.889)
					(mid 0 0.889)
					(end 0 -0.889)
				)
			)
			(stroke
				(width 0)
				(type default)
			)
			(fill no)
			(layer "B.CrtYd")
		)
		(fp_poly
			(pts
				(arc
					(start 0 -0.889)
					(mid 0 0.889)
					(end 0 -0.889)
				)
			)
			(stroke
				(width 0)
				(type default)
			)
			(fill no)
			(layer "F.CrtYd")
		)
		(pad "1" thru_hole circle
			(at 0 0 270)
			(size 0.508 0.508)
			(drill 0.254)
			(layers "*.Cu" "*.Mask")
			(remove_unused_layers no)
			(net "BNO080_EVN_SCL")
			(clearance 0.1016)
			(padstack
				(mode front_inner_back)
				(layer "Inner"
					(shape circle)
					(size 0.508 0.508)
					(clearance 0.1016)
				)
				(layer "B.Cu"
					(shape circle)
					(size 0.762 0.762)
					(clearance -0.0254)
				)
			)
		)
	)
)
